# T6G (Grand Teton) — schematic netlist excerpt (pin names and nets, part order shuffled) for the footprints in the layout excerpt that follows; sources: Cadence DE-HDL packaged netlist, KiCad conversion of 04192023_DAF0TMB3IC0_F0TG_MB_C_brd_V02_OCP.brd

Q50  MOSFET_NCH_DUAL  PJT138K IC  pkg SOT363XD  page 85
  S1  = GND
  G1  = PWRGD_P5V_AUX
  D2  = PWRGD_P5V_AUX_R2
  S2  = GND
  G2  = PWRGD_P5V_AUX_R1
  D1  = PWRGD_P5V_AUX_R1

C2504  Q_CAP  22UF 4V 20% X6S  pkg C0402  page 74 : A = PVDD11_S3_P1 ; B = GND
PC254  Q_CAP  22UF 16V 20% X6S  pkg C0805  page 209 : A = SW_P12V_AUX_PVDD18_S5_P0_FLT ; B = GND

(kicad_pcb
	(version 20260206)
	(generator "pcbnew")
	(generator_version "10.0")
	(general
		(thickness 1.6)
		(legacy_teardrops no)
	)
	(paper "A4")
	(title_block
		(title "04192023_DAF0TMB3IC0_F0TG_MB_C_brd_V02_OCP.brd")
		(comment 1 "Grand Teton / footprints 74-76 of 8354")
	)
	(layers
		(0 "F.Cu" signal "TOP")
		(4 "In1.Cu" signal "GND")
		(6 "In2.Cu" signal "IN1")
		(8 "In3.Cu" signal "GND1")
		(10 "In4.Cu" signal "IN2")
		(12 "In5.Cu" signal "GND2")
		(14 "In6.Cu" signal "IN3")
		(16 "In7.Cu" signal "GND3")
		(18 "In8.Cu" signal "VCC")
		(20 "In9.Cu" signal "VCC1")
		(22 "In10.Cu" signal "GND4")
		(24 "In11.Cu" signal "IN4")
		(26 "In12.Cu" signal "GND5")
		(28 "In13.Cu" signal "IN5")
		(30 "In14.Cu" signal "GND6")
		(32 "In15.Cu" signal "IN6")
		(34 "In16.Cu" signal "GND7")
		(2 "B.Cu" signal "BOTTOM")
		(9 "F.Adhes" user "F.Adhesive")
		(11 "B.Adhes" user "B.Adhesive")
		(13 "F.Paste" user "Package Geometry/Pastemask Top")
		(15 "B.Paste" user "Package Geometry/Pastemask Bottom")
		(5 "F.SilkS" user "Ref Des/Silkscreen Top")
		(7 "B.SilkS" user "Ref Des/Silkscreen Bottom")
		(1 "F.Mask" user "Board Geometry/Soldermask Top")
		(3 "B.Mask" user "Board Geometry/Soldermask Bottom")
		(17 "Dwgs.User" user "User.Drawings")
		(19 "Cmts.User" user "User.Comments")
		(21 "Eco1.User" user "User.Eco1")
		(23 "Eco2.User" user "User.Eco2")
		(25 "Edge.Cuts" user "Board Geometry/Outline")
		(27 "Margin" user)
		(31 "F.CrtYd" user "Package Geometry/Place Bound Top")
		(29 "B.CrtYd" user "Package Geometry/Place Bound Bottom")
		(35 "F.Fab" user "Ref Des/Assembly Top")
		(33 "B.Fab" user "Ref Des/Assembly Bottom")
	)
	(footprint ""
		(layer "F.Cu")
		(at 110.527084 -261.748016 -90)
		(property "Reference" "C2504"
			(at 0 0 270)
			(layer "F.SilkS")
			(hide yes)
			(effects
				(font
					(size 1.27 1.27)
				)
			)
		)
		(property "Value" ""
			(at 0 0 270)
			(layer "F.Fab")
			(effects
				(font
					(size 1.27 1.27)
				)
			)
		)
		(duplicate_pad_numbers_are_jumpers no)
		(fp_line
			(start -0.7874 0.4064)
			(end -0.7874 -0.4064)
			(stroke
				(width 0.1524)
				(type default)
			)
			(layer "F.SilkS")
		)
		(fp_line
			(start 0.7874 0.4064)
			(end -0.7874 0.4064)
			(stroke
				(width 0.1524)
				(type default)
			)
			(layer "F.SilkS")
		)
		(fp_line
			(start -0.7874 -0.4064)
			(end 0.7874 -0.4064)
			(stroke
				(width 0.1524)
				(type default)
			)
			(layer "F.SilkS")
		)
		(fp_line
			(start 0.7874 -0.4064)
			(end 0.7874 0.4064)
			(stroke
				(width 0.1524)
				(type default)
			)
			(layer "F.SilkS")
		)
		(fp_line
			(start -0.67945 0.3048)
			(end -0.67945 -0.305054)
			(stroke
				(width 0.1)
				(type default)
			)
			(layer "F.Fab")
		)
		(fp_line
			(start -0.12065 0.3048)
			(end -0.67945 0.3048)
			(stroke
				(width 0.1)
				(type default)
			)
			(layer "F.Fab")
		)
		(fp_line
			(start 0.120396 0.3048)
			(end 0.120396 0.2794)
			(stroke
				(width 0.1)
				(type default)
			)
			(layer "F.Fab")
		)
		(fp_line
			(start 0.67945 0.3048)
			(end 0.120396 0.3048)
			(stroke
				(width 0.1)
				(type default)
			)
			(layer "F.Fab")
		)
		(fp_line
			(start -0.12065 0.2794)
			(end -0.12065 0.3048)
			(stroke
				(width 0.1)
				(type default)
			)
			(layer "F.Fab")
		)
		(fp_line
			(start 0.120396 0.2794)
			(end -0.12065 0.2794)
			(stroke
				(width 0.1)
				(type default)
			)
			(layer "F.Fab")
		)
		(fp_line
			(start -0.12065 -0.2794)
			(end 0.12065 -0.2794)
			(stroke
				(width 0.1)
				(type default)
			)
			(layer "F.Fab")
		)
		(fp_line
			(start 0.12065 -0.2794)
			(end 0.12065 -0.3048)
			(stroke
				(width 0.1)
				(type default)
			)
			(layer "F.Fab")
		)
		(fp_line
			(start 0.12065 -0.3048)
			(end 0.67945 -0.3048)
			(stroke
				(width 0.1)
				(type default)
			)
			(layer "F.Fab")
		)
		(fp_line
			(start 0.67945 -0.3048)
			(end 0.67945 0.3048)
			(stroke
				(width 0.1)
				(type default)
			)
			(layer "F.Fab")
		)
		(fp_line
			(start -0.67945 -0.305054)
			(end -0.12065 -0.305054)
			(stroke
				(width 0.1)
				(type default)
			)
			(layer "F.Fab")
		)
		(fp_line
			(start -0.12065 -0.305054)
			(end -0.12065 -0.2794)
			(stroke
				(width 0.1)
				(type default)
			)
			(layer "F.Fab")
		)
		(pad "1" smd circle
			(at -0.40005 0 270)
			(size 0 0)
			(layers "F.Cu" "F.Mask" "F.Paste")
			(net "PVDD11_S3_P1")
		)
		(pad "2" smd circle
			(at 0.40005 0 270)
			(size 0 0)
			(layers "F.Cu" "F.Mask" "F.Paste")
			(net "GND")
		)
	)
	(footprint ""
		(layer "F.Cu")
		(at 403.013418 -135.58139 180)
		(property "Reference" "Q50"
			(at 0.719074 2.0066 0)
			(unlocked yes)
			(layer "F.SilkS")
			(effects
				(font
					(size 0.7874 0.5842)
					(thickness 0.1524)
				)
				(justify left)
			)
		)
		(property "Value" ""
			(at 0 0 180)
			(layer "F.Fab")
			(effects
				(font
					(size 1.27 1.27)
				)
			)
		)
		(duplicate_pad_numbers_are_jumpers no)
		(fp_line
			(start 1.332738 1.100074)
			(end -1.332738 1.100074)
			(stroke
				(width 0.1524)
				(type default)
			)
			(layer "F.SilkS")
		)
		(fp_line
			(start 1.332738 -1.100074)
			(end 1.332738 1.100074)
			(stroke
				(width 0.1524)
				(type default)
			)
			(layer "F.SilkS")
		)
		(fp_line
			(start 0.4826 -1.100074)
			(end 1.332738 -1.100074)
			(stroke
				(width 0.1524)
				(type default)
			)
			(layer "F.SilkS")
		)
		(fp_line
			(start 0 -0.541274)
			(end 0.4826 -1.100074)
			(stroke
				(width 0.1524)
				(type default)
			)
			(layer "F.SilkS")
		)
		(fp_line
			(start -0.4826 -1.100074)
			(end 0 -0.541274)
			(stroke
				(width 0.1524)
				(type default)
			)
			(layer "F.SilkS")
		)
		(fp_line
			(start -1.332738 1.100074)
			(end -1.332738 -1.100074)
			(stroke
				(width 0.1524)
				(type default)
			)
			(layer "F.SilkS")
		)
		(fp_line
			(start -1.332738 -1.100074)
			(end -0.4826 -1.100074)
			(stroke
				(width 0.1524)
				(type default)
			)
			(layer "F.SilkS")
		)
		(fp_poly
			(pts
				(xy -1.823212 -0.905764) (xy -2.525268 -0.554736) (xy -2.525268 -1.256792)
			)
			(stroke
				(width 0)
				(type default)
			)
			(fill yes)
			(layer "F.SilkS")
		)
		(fp_line
			(start 0.674878 1.100074)
			(end -0.674878 1.100074)
			(stroke
				(width 0.1)
				(type default)
			)
			(layer "F.Fab")
		)
		(fp_line
			(start 0.674878 -1.100074)
			(end 0.674878 1.100074)
			(stroke
				(width 0.1)
				(type default)
			)
			(layer "F.Fab")
		)
		(fp_line
			(start -0.674878 1.100074)
			(end -0.674878 -1.100074)
			(stroke
				(width 0.1)
				(type default)
			)
			(layer "F.Fab")
		)
		(fp_line
			(start -0.674878 -1.100074)
			(end 0.674878 -1.100074)
			(stroke
				(width 0.1)
				(type default)
			)
			(layer "F.Fab")
		)
		(fp_poly
			(pts
				(xy -2.2352 -0.298958) (xy -2.2352 -1.001014) (xy -1.533144 -0.649986)
			)
			(stroke
				(width 0)
				(type default)
			)
			(fill yes)
			(layer "F.Fab")
		)
		(pad "1" smd rect
			(at -0.94996 -0.649986 270)
			(size 0.4318 0.508)
			(layers "F.Cu" "F.Mask" "F.Paste")
			(net "GND")
		)
		(pad "2" smd rect
			(at -0.94996 0 270)
			(size 0.4318 0.508)
			(layers "F.Cu" "F.Mask" "F.Paste")
			(net "PWRGD_P5V_AUX")
		)
		(pad "3" smd rect
			(at -0.94996 0.649986 270)
			(size 0.4318 0.508)
			(layers "F.Cu" "F.Mask" "F.Paste")
			(net "PWRGD_P5V_AUX_R2")
		)
		(pad "4" smd rect
			(at 0.94996 0.649986 270)
			(size 0.4318 0.508)
			(layers "F.Cu" "F.Mask" "F.Paste")
			(net "GND")
		)
		(pad "5" smd rect
			(at 0.94996 0 270)
			(size 0.4318 0.508)
			(layers "F.Cu" "F.Mask" "F.Paste")
			(net "PWRGD_P5V_AUX_R1")
		)
		(pad "6" smd rect
			(at 0.94996 -0.649986 270)
			(size 0.4318 0.508)
			(layers "F.Cu" "F.Mask" "F.Paste")
			(net "PWRGD_P5V_AUX_R1")
		)
	)
	(footprint ""
		(layer "F.Cu")
		(at 332.807564 -135.156702 180)
		(property "Reference" "PC254"
			(at 0 0 180)
			(layer "F.SilkS")
			(hide yes)
			(effects
				(font
					(size 1.27 1.27)
				)
			)
		)
		(property "Value" ""
			(at 0 0 180)
			(layer "F.Fab")
			(effects
				(font
					(size 1.27 1.27)
				)
			)
		)
		(duplicate_pad_numbers_are_jumpers no)
		(fp_line
			(start 1.524 0.762)
			(end -1.524 0.762)
			(stroke
				(width 0.1524)
				(type default)
			)
			(layer "F.SilkS")
		)
		(fp_line
			(start 1.524 -0.762)
			(end 1.524 0.762)
			(stroke
				(width 0.1524)
				(type default)
			)
			(layer "F.SilkS")
		)
		(fp_line
			(start -1.524 0.762)
			(end -1.524 -0.762)
			(stroke
				(width 0.1524)
				(type default)
			)
			(layer "F.SilkS")
		)
		(fp_line
			(start -1.524 -0.762)
			(end 1.524 -0.762)
			(stroke
				(width 0.1524)
				(type default)
			)
			(layer "F.SilkS")
		)
		(fp_line
			(start 1.1049 0.724916)
			(end 1.1049 -0.724916)
			(stroke
				(width 0.1)
				(type default)
			)
			(layer "F.Fab")
		)
		(fp_line
			(start 1.1049 -0.724916)
			(end -1.1049 -0.724916)
			(stroke
				(width 0.1)
				(type default)
			)
			(layer "F.Fab")
		)
		(fp_line
			(start -1.1049 0.724916)
			(end 1.1049 0.724916)
			(stroke
				(width 0.1)
				(type default)
			)
			(layer "F.Fab")
		)
		(fp_line
			(start -1.1049 -0.724916)
			(end -1.1049 0.724916)
			(stroke
				(width 0.1)
				(type default)
			)
			(layer "F.Fab")
		)
		(pad "1" smd rect
			(at -0.889 0)
			(size 1.016 1.27)
			(layers "F.Cu" "F.Mask" "F.Paste")
			(net "SW_P12V_AUX_PVDD18_S5_P0_FLT")
		)
		(pad "2" smd rect
			(at 0.889 0)
			(size 1.016 1.27)
			(layers "F.Cu" "F.Mask" "F.Paste")
			(net "GND")
		)
	)
)
